(kicad_pcb
	(version 20260206)
	(generator "pcbnew")
	(generator_version "10.0")
	(general
		(thickness 1.6)
		(legacy_teardrops no)
	)
	(paper "A4")
	(title_block
		(title "Bryce Canyon_R.DPB_16317-1_OCP.brd")
		(comment 1 "Bryce Canyon / footprint 692 of 2099 (DPB2), pads 1-54 of 54")
	)
	(layers
		(0 "F.Cu" signal "TOP")
		(4 "In1.Cu" signal "L2GND")
		(6 "In2.Cu" signal "L3")
		(8 "In3.Cu" signal "L4VCC")
		(10 "In4.Cu" signal "L5VCC")
		(12 "In5.Cu" signal "L6")
		(14 "In6.Cu" signal "L7GND")
		(2 "B.Cu" signal "BOTTOM")
		(9 "F.Adhes" user "F.Adhesive")
		(11 "B.Adhes" user "B.Adhesive")
		(13 "F.Paste" user "Package Geometry/Pastemask Top")
		(15 "B.Paste" user "Package Geometry/Pastemask Bottom")
		(5 "F.SilkS" user "Ref Des/Silkscreen Top")
		(7 "B.SilkS" user "Ref Des/Silkscreen Bottom")
		(1 "F.Mask" user "Board Geometry/Soldermask Top")
		(3 "B.Mask" user "Board Geometry/Soldermask Bottom")
		(17 "Dwgs.User" user "User.Drawings")
		(19 "Cmts.User" user "User.Comments")
		(21 "Eco1.User" user "User.Eco1")
		(23 "Eco2.User" user "User.Eco2")
		(25 "Edge.Cuts" user "Board Geometry/Outline")
		(27 "Margin" user)
		(31 "F.CrtYd" user "Package Geometry/Place Bound Top")
		(29 "B.CrtYd" user "Package Geometry/Place Bound Bottom")
		(35 "F.Fab" user "Ref Des/Assembly Top")
		(33 "B.Fab" user "Ref Des/Assembly Bottom")
	)
	(footprint ""
		(layer "F.Cu")
		(at 264.999978 -65.000124 180)
		(property "Reference" "DPB2"
			(at 0 0 180)
			(layer "F.SilkS")
			(hide yes)
			(effects
				(font
					(size 1.27 1.27)
				)
			)
		)
		(property "Value" "AMP-CONN54-6R-1-GP"
			(at 31.115 10.541 180)
			(unlocked yes)
			(layer "F.Fab")
			(hide yes)
			(effects
				(font
					(size 1.016 1.016)
					(thickness 0.1524)
				)
			)
		)
		(property "Device Type" "PREFIT-54P-216327H571"
			(at 31.115 9.017 180)
			(unlocked yes)
			(layer "F.Fab")
			(hide yes)
			(effects
				(font
					(size 1.016 1.016)
					(thickness 0.1524)
				)
			)
		)
		(duplicate_pad_numbers_are_jumpers no)
		(pad "A1" thru_hole circle
			(at 0 0 180)
			(size 1.2192 1.2192)
			(drill 0.739902)
			(layers "*.Cu" "*.Mask")
			(remove_unused_layers no)
			(net "P12V_IN")
			(clearance 0.127)
			(thermal_gap 0.127)
		)
		(pad "A2" thru_hole circle
			(at 3.199892 0 180)
			(size 1.2192 1.2192)
			(drill 0.739902)
			(layers "*.Cu" "*.Mask")
			(remove_unused_layers no)
			(net "P12V_IN")
			(clearance 0.127)
			(thermal_gap 0.127)
		)
		(pad "A3" thru_hole circle
			(at 7.200138 0 180)
			(size 1.2192 1.2192)
			(drill 0.739902)
			(layers "*.Cu" "*.Mask")
			(remove_unused_layers no)
			(net "P12V_IN")
			(clearance 0.127)
			(thermal_gap 0.127)
		)
		(pad "A4" thru_hole circle
			(at 10.40003 0 180)
			(size 1.2192 1.2192)
			(drill 0.739902)
			(layers "*.Cu" "*.Mask")
			(remove_unused_layers no)
			(net "P12V_IN")
			(clearance 0.127)
			(thermal_gap 0.127)
		)
		(pad "A5" thru_hole circle
			(at 14.400022 0 180)
			(size 1.2192 1.2192)
			(drill 0.739902)
			(layers "*.Cu" "*.Mask")
			(remove_unused_layers no)
			(net "P12V_B")
			(clearance 0.127)
			(thermal_gap 0.127)
		)
		(pad "A6" thru_hole circle
			(at 17.600168 0 180)
			(size 1.2192 1.2192)
			(drill 0.739902)
			(layers "*.Cu" "*.Mask")
			(remove_unused_layers no)
			(net "P12V_B")
			(clearance 0.127)
			(thermal_gap 0.127)
		)
		(pad "B1" thru_hole oval
			(at 0 1.500124 180)
			(size 1.2192 4.2164)
			(drill 0.739902)
			(layers "*.Cu" "*.Mask")
			(remove_unused_layers no)
			(net "P12V_IN")
			(clearance 0.127)
			(thermal_gap 0.127)
			(padstack
				(mode front_inner_back)
				(layer "Inner"
					(shape circle)
					(size 1.2192 1.2192)
					(clearance 0.127)
				)
				(layer "B.Cu"
					(shape circle)
					(size 1.2192 1.2192)
					(clearance 0.127)
				)
			)
		)
		(pad "B2" thru_hole oval
			(at 3.199892 1.500124 180)
			(size 1.2192 4.2164)
			(drill 0.739902)
			(layers "*.Cu" "*.Mask")
			(remove_unused_layers no)
			(net "P12V_IN")
			(clearance 0.127)
			(thermal_gap 0.127)
			(padstack
				(mode front_inner_back)
				(layer "Inner"
					(shape circle)
					(size 1.2192 1.2192)
					(clearance 0.127)
				)
				(layer "B.Cu"
					(shape circle)
					(size 1.2192 1.2192)
					(clearance 0.127)
				)
			)
		)
		(pad "B3" thru_hole oval
			(at 7.200138 1.500124 180)
			(size 1.2192 4.2164)
			(drill 0.739902)
			(layers "*.Cu" "*.Mask")
			(remove_unused_layers no)
			(net "P12V_IN")
			(clearance 0.127)
			(thermal_gap 0.127)
			(padstack
				(mode front_inner_back)
				(layer "Inner"
					(shape circle)
					(size 1.2192 1.2192)
					(clearance 0.127)
				)
				(layer "B.Cu"
					(shape circle)
					(size 1.2192 1.2192)
					(clearance 0.127)
				)
			)
		)
		(pad "B4" thru_hole oval
			(at 10.40003 1.500124 180)
			(size 1.2192 4.2164)
			(drill 0.739902)
			(layers "*.Cu" "*.Mask")
			(remove_unused_layers no)
			(net "P12V_IN")
			(clearance 0.127)
			(thermal_gap 0.127)
			(padstack
				(mode front_inner_back)
				(layer "Inner"
					(shape circle)
					(size 1.2192 1.2192)
					(clearance 0.127)
				)
				(layer "B.Cu"
					(shape circle)
					(size 1.2192 1.2192)
					(clearance 0.127)
				)
			)
		)
		(pad "B5" thru_hole oval
			(at 14.400022 1.500124 180)
			(size 1.2192 4.2164)
			(drill 0.739902)
			(layers "*.Cu" "*.Mask")
			(remove_unused_layers no)
			(net "P12V_B")
			(clearance 0.127)
			(thermal_gap 0.127)
			(padstack
				(mode front_inner_back)
				(layer "Inner"
					(shape circle)
					(size 1.2192 1.2192)
					(clearance 0.127)
				)
				(layer "B.Cu"
					(shape circle)
					(size 1.2192 1.2192)
					(clearance 0.127)
				)
			)
		)
		(pad "B6" thru_hole oval
			(at 17.600168 1.500124 180)
			(size 1.2192 4.2164)
			(drill 0.739902)
			(layers "*.Cu" "*.Mask")
			(remove_unused_layers no)
			(net "P12V_B")
			(clearance 0.127)
			(thermal_gap 0.127)
			(padstack
				(mode front_inner_back)
				(layer "Inner"
					(shape circle)
					(size 1.2192 1.2192)
					(clearance 0.127)
				)
				(layer "B.Cu"
					(shape circle)
					(size 1.2192 1.2192)
					(clearance 0.127)
				)
			)
		)
		(pad "C1" thru_hole circle
			(at 0 2.999994 180)
			(size 1.2192 1.2192)
			(drill 0.739902)
			(layers "*.Cu" "*.Mask")
			(remove_unused_layers no)
			(net "P12V_IN")
			(clearance 0.127)
			(thermal_gap 0.127)
		)
		(pad "C2" thru_hole circle
			(at 3.199892 2.999994 180)
			(size 1.2192 1.2192)
			(drill 0.739902)
			(layers "*.Cu" "*.Mask")
			(remove_unused_layers no)
			(net "P12V_IN")
			(clearance 0.127)
			(thermal_gap 0.127)
		)
		(pad "C3" thru_hole circle
			(at 7.200138 2.999994 180)
			(size 1.2192 1.2192)
			(drill 0.739902)
			(layers "*.Cu" "*.Mask")
			(remove_unused_layers no)
			(net "P12V_IN")
			(clearance 0.127)
			(thermal_gap 0.127)
		)
		(pad "C4" thru_hole circle
			(at 10.40003 2.999994 180)
			(size 1.2192 1.2192)
			(drill 0.739902)
			(layers "*.Cu" "*.Mask")
			(remove_unused_layers no)
			(net "P12V_IN")
			(clearance 0.127)
			(thermal_gap 0.127)
		)
		(pad "C5" thru_hole circle
			(at 14.400022 2.999994 180)
			(size 1.2192 1.2192)
			(drill 0.739902)
			(layers "*.Cu" "*.Mask")
			(remove_unused_layers no)
			(net "P12V_B")
			(clearance 0.127)
			(thermal_gap 0.127)
		)
		(pad "C6" thru_hole circle
			(at 17.600168 2.999994 180)
			(size 1.2192 1.2192)
			(drill 0.739902)
			(layers "*.Cu" "*.Mask")
			(remove_unused_layers no)
			(net "P12V_B")
			(clearance 0.127)
			(thermal_gap 0.127)
		)
		(pad "D1" thru_hole circle
			(at 0 5.750052 180)
			(size 1.2192 1.2192)
			(drill 0.739902)
			(layers "*.Cu" "*.Mask")
			(remove_unused_layers no)
			(net "P12V_IN")
			(clearance 0.127)
			(thermal_gap 0.127)
		)
		(pad "D2" thru_hole circle
			(at 3.199892 5.750052 180)
			(size 1.2192 1.2192)
			(drill 0.739902)
			(layers "*.Cu" "*.Mask")
			(remove_unused_layers no)
			(net "P12V_IN")
			(clearance 0.127)
			(thermal_gap 0.127)
		)
		(pad "D3" thru_hole circle
			(at 7.200138 5.750052 180)
			(size 1.2192 1.2192)
			(drill 0.739902)
			(layers "*.Cu" "*.Mask")
			(remove_unused_layers no)
			(net "P12V_IN")
			(clearance 0.127)
			(thermal_gap 0.127)
		)
		(pad "D4" thru_hole circle
			(at 10.40003 5.750052 180)
			(size 1.2192 1.2192)
			(drill 0.739902)
			(layers "*.Cu" "*.Mask")
			(remove_unused_layers no)
			(net "P12V_IN")
			(clearance 0.127)
			(thermal_gap 0.127)
		)
		(pad "D5" thru_hole circle
			(at 14.400022 5.750052 180)
			(size 1.2192 1.2192)
			(drill 0.739902)
			(layers "*.Cu" "*.Mask")
			(remove_unused_layers no)
			(net "GND")
			(clearance 0.127)
			(thermal_gap 0.127)
		)
		(pad "D6" thru_hole circle
			(at 17.600168 5.750052 180)
			(size 1.2192 1.2192)
			(drill 0.739902)
			(layers "*.Cu" "*.Mask")
			(remove_unused_layers no)
			(net "GND")
			(clearance 0.127)
			(thermal_gap 0.127)
		)
		(pad "E1" thru_hole oval
			(at 0 7.249922 180)
			(size 1.2192 4.2164)
			(drill 0.739902)
			(layers "*.Cu" "*.Mask")
			(remove_unused_layers no)
			(net "P12V_IN")
			(clearance 0.127)
			(thermal_gap 0.127)
			(padstack
				(mode front_inner_back)
				(layer "Inner"
					(shape circle)
					(size 1.2192 1.2192)
					(clearance 0.127)
				)
				(layer "B.Cu"
					(shape circle)
					(size 1.2192 1.2192)
					(clearance 0.127)
				)
			)
		)
		(pad "E2" thru_hole oval
			(at 3.199892 7.249922 180)
			(size 1.2192 4.2164)
			(drill 0.739902)
			(layers "*.Cu" "*.Mask")
			(remove_unused_layers no)
			(net "P12V_IN")
			(clearance 0.127)
			(thermal_gap 0.127)
			(padstack
				(mode front_inner_back)
				(layer "Inner"
					(shape circle)
					(size 1.2192 1.2192)
					(clearance 0.127)
				)
				(layer "B.Cu"
					(shape circle)
					(size 1.2192 1.2192)
					(clearance 0.127)
				)
			)
		)
		(pad "E3" thru_hole oval
			(at 7.200138 7.249922 180)
			(size 1.2192 4.2164)
			(drill 0.739902)
			(layers "*.Cu" "*.Mask")
			(remove_unused_layers no)
			(net "P12V_IN")
			(clearance 0.127)
			(thermal_gap 0.127)
			(padstack
				(mode front_inner_back)
				(layer "Inner"
					(shape circle)
					(size 1.2192 1.2192)
					(clearance 0.127)
				)
				(layer "B.Cu"
					(shape circle)
					(size 1.2192 1.2192)
					(clearance 0.127)
				)
			)
		)
		(pad "E4" thru_hole oval
			(at 10.40003 7.249922 180)
			(size 1.2192 4.2164)
			(drill 0.739902)
			(layers "*.Cu" "*.Mask")
			(remove_unused_layers no)
			(net "P12V_IN")
			(clearance 0.127)
			(thermal_gap 0.127)
			(padstack
				(mode front_inner_back)
				(layer "Inner"
					(shape circle)
					(size 1.2192 1.2192)
					(clearance 0.127)
				)
				(layer "B.Cu"
					(shape circle)
					(size 1.2192 1.2192)
					(clearance 0.127)
				)
			)
		)
		(pad "E5" thru_hole oval
			(at 14.400022 7.249922 180)
			(size 1.2192 4.2164)
			(drill 0.739902)
			(layers "*.Cu" "*.Mask")
			(remove_unused_layers no)
			(net "GND")
			(clearance 0.127)
			(thermal_gap 0.127)
			(padstack
				(mode front_inner_back)
				(layer "Inner"
					(shape circle)
					(size 1.2192 1.2192)
					(clearance 0.127)
				)
				(layer "B.Cu"
					(shape circle)
					(size 1.2192 1.2192)
					(clearance 0.127)
				)
			)
		)
		(pad "E6" thru_hole oval
			(at 17.600168 7.249922 180)
			(size 1.2192 4.2164)
			(drill 0.739902)
			(layers "*.Cu" "*.Mask")
			(remove_unused_layers no)
			(net "GND")
			(clearance 0.127)
			(thermal_gap 0.127)
			(padstack
				(mode front_inner_back)
				(layer "Inner"
					(shape circle)
					(size 1.2192 1.2192)
					(clearance 0.127)
				)
				(layer "B.Cu"
					(shape circle)
					(size 1.2192 1.2192)
					(clearance 0.127)
				)
			)
		)
		(pad "F1" thru_hole circle
			(at 0 8.750046 180)
			(size 1.2192 1.2192)
			(drill 0.739902)
			(layers "*.Cu" "*.Mask")
			(remove_unused_layers no)
			(net "P12V_IN")
			(clearance 0.127)
			(thermal_gap 0.127)
		)
		(pad "F2" thru_hole circle
			(at 3.199892 8.750046 180)
			(size 1.2192 1.2192)
			(drill 0.739902)
			(layers "*.Cu" "*.Mask")
			(remove_unused_layers no)
			(net "P12V_IN")
			(clearance 0.127)
			(thermal_gap 0.127)
		)
		(pad "F3" thru_hole circle
			(at 7.200138 8.750046 180)
			(size 1.2192 1.2192)
			(drill 0.739902)
			(layers "*.Cu" "*.Mask")
			(remove_unused_layers no)
			(net "P12V_IN")
			(clearance 0.127)
			(thermal_gap 0.127)
		)
		(pad "F4" thru_hole circle
			(at 10.40003 8.750046 180)
			(size 1.2192 1.2192)
			(drill 0.739902)
			(layers "*.Cu" "*.Mask")
			(remove_unused_layers no)
			(net "P12V_IN")
			(clearance 0.127)
			(thermal_gap 0.127)
		)
		(pad "F5" thru_hole circle
			(at 14.400022 8.750046 180)
			(size 1.2192 1.2192)
			(drill 0.739902)
			(layers "*.Cu" "*.Mask")
			(remove_unused_layers no)
			(net "GND")
			(clearance 0.127)
			(thermal_gap 0.127)
		)
		(pad "F6" thru_hole circle
			(at 17.600168 8.750046 180)
			(size 1.2192 1.2192)
			(drill 0.739902)
			(layers "*.Cu" "*.Mask")
			(remove_unused_layers no)
			(net "GND")
			(clearance 0.127)
			(thermal_gap 0.127)
		)
		(pad "G1" thru_hole circle
			(at 0 11.500104 180)
			(size 1.2192 1.2192)
			(drill 0.739902)
			(layers "*.Cu" "*.Mask")
			(remove_unused_layers no)
			(net "GND")
			(clearance 0.127)
			(thermal_gap 0.127)
		)
		(pad "G2" thru_hole circle
			(at 3.199892 11.500104 180)
			(size 1.2192 1.2192)
			(drill 0.739902)
			(layers "*.Cu" "*.Mask")
			(remove_unused_layers no)
			(net "GND")
			(clearance 0.127)
			(thermal_gap 0.127)
		)
		(pad "G3" thru_hole circle
			(at 7.200138 11.500104 180)
			(size 1.2192 1.2192)
			(drill 0.739902)
			(layers "*.Cu" "*.Mask")
			(remove_unused_layers no)
			(net "GND")
			(clearance 0.127)
			(thermal_gap 0.127)
		)
		(pad "G4" thru_hole circle
			(at 10.40003 11.500104 180)
			(size 1.2192 1.2192)
			(drill 0.739902)
			(layers "*.Cu" "*.Mask")
			(remove_unused_layers no)
			(net "GND")
			(clearance 0.127)
			(thermal_gap 0.127)
		)
		(pad "G5" thru_hole circle
			(at 14.400022 11.500104 180)
			(size 1.2192 1.2192)
			(drill 0.739902)
			(layers "*.Cu" "*.Mask")
			(remove_unused_layers no)
			(net "GND")
			(clearance 0.127)
			(thermal_gap 0.127)
		)
		(pad "G6" thru_hole circle
			(at 17.600168 11.500104 180)
			(size 1.2192 1.2192)
			(drill 0.739902)
			(layers "*.Cu" "*.Mask")
			(remove_unused_layers no)
			(net "GND")
			(clearance 0.127)
			(thermal_gap 0.127)
		)
		(pad "H1" thru_hole oval
			(at 0 12.999974 180)
			(size 1.2192 4.2164)
			(drill 0.739902)
			(layers "*.Cu" "*.Mask")
			(remove_unused_layers no)
			(net "GND")
			(clearance 0.127)
			(thermal_gap 0.127)
			(padstack
				(mode front_inner_back)
				(layer "Inner"
					(shape circle)
					(size 1.2192 1.2192)
					(clearance 0.127)
				)
				(layer "B.Cu"
					(shape circle)
					(size 1.2192 1.2192)
					(clearance 0.127)
				)
			)
		)
		(pad "H2" thru_hole oval
			(at 3.199892 12.999974 180)
			(size 1.2192 4.2164)
			(drill 0.739902)
			(layers "*.Cu" "*.Mask")
			(remove_unused_layers no)
			(net "GND")
			(clearance 0.127)
			(thermal_gap 0.127)
			(padstack
				(mode front_inner_back)
				(layer "Inner"
					(shape circle)
					(size 1.2192 1.2192)
					(clearance 0.127)
				)
				(layer "B.Cu"
					(shape circle)
					(size 1.2192 1.2192)
					(clearance 0.127)
				)
			)
		)
		(pad "H3" thru_hole oval
			(at 7.200138 12.999974 180)
			(size 1.2192 4.2164)
			(drill 0.739902)
			(layers "*.Cu" "*.Mask")
			(remove_unused_layers no)
			(net "GND")
			(clearance 0.127)
			(thermal_gap 0.127)
			(padstack
				(mode front_inner_back)
				(layer "Inner"
					(shape circle)
					(size 1.2192 1.2192)
					(clearance 0.127)
				)
				(layer "B.Cu"
					(shape circle)
					(size 1.2192 1.2192)
					(clearance 0.127)
				)
			)
		)
		(pad "H4" thru_hole oval
			(at 10.40003 12.999974 180)
			(size 1.2192 4.2164)
			(drill 0.739902)
			(layers "*.Cu" "*.Mask")
			(remove_unused_layers no)
			(net "GND")
			(clearance 0.127)
			(thermal_gap 0.127)
			(padstack
				(mode front_inner_back)
				(layer "Inner"
					(shape circle)
					(size 1.2192 1.2192)
					(clearance 0.127)
				)
				(layer "B.Cu"
					(shape circle)
					(size 1.2192 1.2192)
					(clearance 0.127)
				)
			)
		)
		(pad "H5" thru_hole oval
			(at 14.400022 12.999974 180)
			(size 1.2192 4.2164)
			(drill 0.739902)
			(layers "*.Cu" "*.Mask")
			(remove_unused_layers no)
			(net "GND")
			(clearance 0.127)
			(thermal_gap 0.127)
			(padstack
				(mode front_inner_back)
				(layer "Inner"
					(shape circle)
					(size 1.2192 1.2192)
					(clearance 0.127)
				)
				(layer "B.Cu"
					(shape circle)
					(size 1.2192 1.2192)
					(clearance 0.127)
				)
			)
		)
		(pad "H6" thru_hole oval
			(at 17.600168 12.999974 180)
			(size 1.2192 4.2164)
			(drill 0.739902)
			(layers "*.Cu" "*.Mask")
			(remove_unused_layers no)
			(net "GND")
			(clearance 0.127)
			(thermal_gap 0.127)
			(padstack
				(mode front_inner_back)
				(layer "Inner"
					(shape circle)
					(size 1.2192 1.2192)
					(clearance 0.127)
				)
				(layer "B.Cu"
					(shape circle)
					(size 1.2192 1.2192)
					(clearance 0.127)
				)
			)
		)
		(pad "J1" thru_hole circle
			(at 0 14.500098 180)
			(size 1.2192 1.2192)
			(drill 0.739902)
			(layers "*.Cu" "*.Mask")
			(remove_unused_layers no)
			(net "GND")
			(clearance 0.127)
			(thermal_gap 0.127)
		)
		(pad "J2" thru_hole circle
			(at 3.199892 14.500098 180)
			(size 1.2192 1.2192)
			(drill 0.739902)
			(layers "*.Cu" "*.Mask")
			(remove_unused_layers no)
			(net "GND")
			(clearance 0.127)
			(thermal_gap 0.127)
		)
		(pad "J3" thru_hole circle
			(at 7.200138 14.500098 180)
			(size 1.2192 1.2192)
			(drill 0.739902)
			(layers "*.Cu" "*.Mask")
			(remove_unused_layers no)
			(net "GND")
			(clearance 0.127)
			(thermal_gap 0.127)
		)
		(pad "J4" thru_hole circle
			(at 10.40003 14.500098 180)
			(size 1.2192 1.2192)
			(drill 0.739902)
			(layers "*.Cu" "*.Mask")
			(remove_unused_layers no)
			(net "GND")
			(clearance 0.127)
			(thermal_gap 0.127)
		)
		(pad "J5" thru_hole circle
			(at 14.400022 14.500098 180)
			(size 1.2192 1.2192)
			(drill 0.739902)
			(layers "*.Cu" "*.Mask")
			(remove_unused_layers no)
			(net "GND")
			(clearance 0.127)
			(thermal_gap 0.127)
		)
		(pad "J6" thru_hole circle
			(at 17.600168 14.500098 180)
			(size 1.2192 1.2192)
			(drill 0.739902)
			(layers "*.Cu" "*.Mask")
			(remove_unused_layers no)
			(net "GND")
			(clearance 0.127)
			(thermal_gap 0.127)
		)
	)
)
